# T6G (Grand Teton) — schematic netlist excerpt (pin names and nets, part order shuffled) for the footprints in the layout excerpt that follows; sources: Cadence DE-HDL packaged netlist, KiCad conversion of 04192023_DAF0TMB3IC0_F0TG_MB_C_brd_V02_OCP.brd

X8004  TP_TDR_4P_FTS  TP_TDR_4P_DIP EMPTY  pkg TH  page 260
  S1  = TDR_DIFF_85_IN3_DP
  P1  = T1_GND
  P2  = T1_GND
  S2  = TDR_DIFF_85_IN3_DN

R602  Q_RES  33 5% CHIP  pkg 0402LF  page 77 : A = SPI_CPU0_LVC3_CLK ; B = SPI_CPU0_LVC3_SCM_CLK

(kicad_pcb
	(version 20260206)
	(generator "pcbnew")
	(generator_version "10.0")
	(general
		(thickness 1.6)
		(legacy_teardrops no)
	)
	(paper "A4")
	(title_block
		(title "04192023_DAF0TMB3IC0_F0TG_MB_C_brd_V02_OCP.brd")
		(comment 1 "Grand Teton / footprints 3194-3195 of 8354")
	)
	(layers
		(0 "F.Cu" signal "TOP")
		(4 "In1.Cu" signal "GND")
		(6 "In2.Cu" signal "IN1")
		(8 "In3.Cu" signal "GND1")
		(10 "In4.Cu" signal "IN2")
		(12 "In5.Cu" signal "GND2")
		(14 "In6.Cu" signal "IN3")
		(16 "In7.Cu" signal "GND3")
		(18 "In8.Cu" signal "VCC")
		(20 "In9.Cu" signal "VCC1")
		(22 "In10.Cu" signal "GND4")
		(24 "In11.Cu" signal "IN4")
		(26 "In12.Cu" signal "GND5")
		(28 "In13.Cu" signal "IN5")
		(30 "In14.Cu" signal "GND6")
		(32 "In15.Cu" signal "IN6")
		(34 "In16.Cu" signal "GND7")
		(2 "B.Cu" signal "BOTTOM")
		(9 "F.Adhes" user "F.Adhesive")
		(11 "B.Adhes" user "B.Adhesive")
		(13 "F.Paste" user "Package Geometry/Pastemask Top")
		(15 "B.Paste" user "Package Geometry/Pastemask Bottom")
		(5 "F.SilkS" user "Ref Des/Silkscreen Top")
		(7 "B.SilkS" user "Ref Des/Silkscreen Bottom")
		(1 "F.Mask" user "Board Geometry/Soldermask Top")
		(3 "B.Mask" user "Board Geometry/Soldermask Bottom")
		(17 "Dwgs.User" user "User.Drawings")
		(19 "Cmts.User" user "User.Comments")
		(21 "Eco1.User" user "User.Eco1")
		(23 "Eco2.User" user "User.Eco2")
		(25 "Edge.Cuts" user "Board Geometry/Outline")
		(27 "Margin" user)
		(31 "F.CrtYd" user "Package Geometry/Place Bound Top")
		(29 "B.CrtYd" user "Package Geometry/Place Bound Bottom")
		(35 "F.Fab" user "Ref Des/Assembly Top")
		(33 "B.Fab" user "Ref Des/Assembly Bottom")
	)
	(footprint ""
		(layer "F.Cu")
		(at 490.57433 7.610602 -90)
		(property "Reference" "X8004"
			(at -1.859788 4.892802 0)
			(unlocked yes)
			(layer "F.SilkS")
			(effects
				(font
					(size 0.7874 0.5842)
					(thickness 0.1524)
				)
				(justify left)
			)
		)
		(property "Value" ""
			(at 0 0 270)
			(layer "F.Fab")
			(effects
				(font
					(size 1.27 1.27)
				)
			)
		)
		(property "Device Type" "TP_TDR_4P_FTS_TH-TP_TDR_4P_DIP,EMPTY,TP15"
			(at 1.30175 1.27 0)
			(unlocked yes)
			(layer "F.Fab")
			(hide yes)
			(effects
				(font
					(size 0.635 0.4064)
					(thickness 0.1524)
				)
			)
		)
		(property "User Part Number" "N_A"
			(at 1.30175 1.27 0)
			(unlocked yes)
			(layer "Cmts.User")
			(hide yes)
			(effects
				(font
					(size 0.635 0.4064)
					(thickness 0.1524)
				)
			)
		)
		(duplicate_pad_numbers_are_jumpers no)
		(fp_line
			(start 0 3.81)
			(end 2.54 3.81)
			(stroke
				(width 0.1524)
				(type default)
			)
			(layer "F.SilkS")
		)
		(fp_line
			(start 2.54 3.81)
			(end 2.54 3.6703)
			(stroke
				(width 0.1524)
				(type default)
			)
			(layer "F.SilkS")
		)
		(fp_line
			(start 0 3.175)
			(end 0 3.81)
			(stroke
				(width 0.1524)
				(type default)
			)
			(layer "F.SilkS")
		)
		(fp_line
			(start 2.54 1.4097)
			(end 2.54 1.1303)
			(stroke
				(width 0.1524)
				(type default)
			)
			(layer "F.SilkS")
		)
		(fp_line
			(start 0 0.635)
			(end 0 1.905)
			(stroke
				(width 0.1524)
				(type default)
			)
			(layer "F.SilkS")
		)
		(fp_line
			(start 2.54 -1.1303)
			(end 2.54 -1.27)
			(stroke
				(width 0.1524)
				(type default)
			)
			(layer "F.SilkS")
		)
		(fp_line
			(start 0 -1.27)
			(end 0 -0.635)
			(stroke
				(width 0.1524)
				(type default)
			)
			(layer "F.SilkS")
		)
		(fp_line
			(start 2.54 -1.27)
			(end 0 -1.27)
			(stroke
				(width 0.1524)
				(type default)
			)
			(layer "F.SilkS")
		)
		(fp_poly
			(pts
				(xy -2.285746 -0.762) (xy -0.761746 0) (xy -2.285746 0.762)
			)
			(stroke
				(width 0)
				(type default)
			)
			(fill yes)
			(layer "F.SilkS")
		)
		(fp_line
			(start 0 3.81)
			(end 2.54 3.81)
			(stroke
				(width 0.1)
				(type default)
			)
			(layer "F.Fab")
		)
		(fp_line
			(start 2.54 3.81)
			(end 2.54 -1.27)
			(stroke
				(width 0.1)
				(type default)
			)
			(layer "F.Fab")
		)
		(fp_line
			(start 0 -1.27)
			(end 0 3.81)
			(stroke
				(width 0.1)
				(type default)
			)
			(layer "F.Fab")
		)
		(fp_line
			(start 2.54 -1.27)
			(end 0 -1.27)
			(stroke
				(width 0.1)
				(type default)
			)
			(layer "F.Fab")
		)
		(fp_poly
			(pts
				(xy -0.761746 0) (xy -2.285746 -0.762) (xy -2.285746 0.762)
			)
			(stroke
				(width 0)
				(type default)
			)
			(fill yes)
			(layer "F.Fab")
		)
		(pad "1" thru_hole circle
			(at 0 0 270)
			(size 1.0033 1.0033)
			(drill 0.249936)
			(layers "*.Cu" "*.Mask")
			(remove_unused_layers no)
			(net "TDR_DIFF_85_IN3_DP")
			(clearance 0.10795)
			(thermal_gap 0.10795)
			(padstack
				(mode front_inner_back)
				(layer "Inner"
					(shape circle)
					(size 0.8001 0.8001)
					(clearance 0.1524)
				)
				(layer "B.Cu"
					(shape circle)
					(size 1.0033 1.0033)
					(clearance 0.10795)
				)
			)
		)
		(pad "2" thru_hole circle
			(at 2.54 0 270)
			(size 1.9939 1.9939)
			(drill 0.249936)
			(layers "*.Cu" "*.Mask")
			(remove_unused_layers no)
			(net "T1_GND")
			(clearance 0.10795)
			(thermal_gap 0.10795)
			(padstack
				(mode front_inner_back)
				(layer "Inner"
					(shape circle)
					(size 0.8001 0.8001)
					(clearance 0.1524)
				)
				(layer "B.Cu"
					(shape circle)
					(size 1.9939 1.9939)
					(clearance 0.10795)
				)
			)
		)
		(pad "3" thru_hole circle
			(at 2.54 2.54 270)
			(size 1.9939 1.9939)
			(drill 0.249936)
			(layers "*.Cu" "*.Mask")
			(remove_unused_layers no)
			(net "T1_GND")
			(clearance 0.10795)
			(thermal_gap 0.10795)
			(padstack
				(mode front_inner_back)
				(layer "Inner"
					(shape circle)
					(size 0.8001 0.8001)
					(clearance 0.1524)
				)
				(layer "B.Cu"
					(shape circle)
					(size 1.9939 1.9939)
					(clearance 0.10795)
				)
			)
		)
		(pad "4" thru_hole circle
			(at 0 2.54 270)
			(size 1.0033 1.0033)
			(drill 0.249936)
			(layers "*.Cu" "*.Mask")
			(remove_unused_layers no)
			(net "TDR_DIFF_85_IN3_DN")
			(clearance 0.10795)
			(thermal_gap 0.10795)
			(padstack
				(mode front_inner_back)
				(layer "Inner"
					(shape circle)
					(size 0.8001 0.8001)
					(clearance 0.1524)
				)
				(layer "B.Cu"
					(shape circle)
					(size 1.0033 1.0033)
					(clearance 0.10795)
				)
			)
		)
	)
	(footprint ""
		(layer "F.Cu")
		(at 253.506224 -132.337556 180)
		(property "Reference" "R602"
			(at 0 0 180)
			(layer "F.SilkS")
			(hide yes)
			(effects
				(font
					(size 1.27 1.27)
				)
			)
		)
		(property "Value" ""
			(at 0 0 180)
			(layer "F.Fab")
			(effects
				(font
					(size 1.27 1.27)
				)
			)
		)
		(duplicate_pad_numbers_are_jumpers no)
		(fp_line
			(start 0.7874 0.4064)
			(end -0.7874 0.4064)
			(stroke
				(width 0.1524)
				(type default)
			)
			(layer "F.SilkS")
		)
		(fp_line
			(start 0.7874 -0.4064)
			(end 0.7874 0.4064)
			(stroke
				(width 0.1524)
				(type default)
			)
			(layer "F.SilkS")
		)
		(fp_line
			(start -0.7874 0.4064)
			(end -0.7874 -0.4064)
			(stroke
				(width 0.1524)
				(type default)
			)
			(layer "F.SilkS")
		)
		(fp_line
			(start -0.7874 -0.4064)
			(end 0.7874 -0.4064)
			(stroke
				(width 0.1524)
				(type default)
			)
			(layer "F.SilkS")
		)
		(fp_line
			(start 0.67945 0.3048)
			(end 0.120396 0.3048)
			(stroke
				(width 0.1)
				(type default)
			)
			(layer "F.Fab")
		)
		(fp_line
			(start 0.67945 -0.3048)
			(end 0.67945 0.3048)
			(stroke
				(width 0.1)
				(type default)
			)
			(layer "F.Fab")
		)
		(fp_line
			(start 0.12065 -0.2794)
			(end 0.12065 -0.3048)
			(stroke
				(width 0.1)
				(type default)
			)
			(layer "F.Fab")
		)
		(fp_line
			(start 0.12065 -0.3048)
			(end 0.67945 -0.3048)
			(stroke
				(width 0.1)
				(type default)
			)
			(layer "F.Fab")
		)
		(fp_line
			(start 0.120396 0.3048)
			(end 0.120396 0.2794)
			(stroke
				(width 0.1)
				(type default)
			)
			(layer "F.Fab")
		)
		(fp_line
			(start 0.120396 0.2794)
			(end -0.12065 0.2794)
			(stroke
				(width 0.1)
				(type default)
			)
			(layer "F.Fab")
		)
		(fp_line
			(start -0.12065 0.3048)
			(end -0.67945 0.3048)
			(stroke
				(width 0.1)
				(type default)
			)
			(layer "F.Fab")
		)
		(fp_line
			(start -0.12065 0.2794)
			(end -0.12065 0.3048)
			(stroke
				(width 0.1)
				(type default)
			)
			(layer "F.Fab")
		)
		(fp_line
			(start -0.12065 -0.2794)
			(end 0.12065 -0.2794)
			(stroke
				(width 0.1)
				(type default)
			)
			(layer "F.Fab")
		)
		(fp_line
			(start -0.12065 -0.305054)
			(end -0.12065 -0.2794)
			(stroke
				(width 0.1)
				(type default)
			)
			(layer "F.Fab")
		)
		(fp_line
			(start -0.67945 0.3048)
			(end -0.67945 -0.305054)
			(stroke
				(width 0.1)
				(type default)
			)
			(layer "F.Fab")
		)
		(fp_line
			(start -0.67945 -0.305054)
			(end -0.12065 -0.305054)
			(stroke
				(width 0.1)
				(type default)
			)
			(layer "F.Fab")
		)
		(pad "1" smd circle
			(at -0.40005 0 180)
			(size 0 0)
			(layers "F.Cu" "F.Mask" "F.Paste")
			(net "SPI_CPU0_LVC3_CLK")
		)
		(pad "2" smd circle
			(at 0.40005 0 180)
			(size 0 0)
			(layers "F.Cu" "F.Mask" "F.Paste")
			(net "SPI_CPU0_LVC3_SCM_CLK")
		)
	)
)
